# BASEBOARD_FAB2 (Tioga Pass) — schematic netlist excerpt (pin names and nets, part order shuffled) for the footprints in the layout excerpt that follows; sources: Cadence DE-HDL packaged netlist, KiCad conversion of Wiwynn_Tioga_Pass_MB.brd

R4E3  RES  1.00K 1% CHIP  pkg 0402  page 201 : A = P3V3_STBY ; B = IRQ_PVCCIN_CPU0_VRHOT_LVC3_R_N
R2U40  RES  150.0 1% CHIP  pkg 0402  page 152 : A = PVCCIO_CPU0 ; B = H_CPU0_MEMABC_MEMHOT_G_N
C1E3  CAP_A  22.0UF 4V 20% X6S  pkg 0603V  page 207 : A = PVCCIN_CPU1 ; B = GND

(kicad_pcb
	(version 20260206)
	(generator "pcbnew")
	(generator_version "10.0")
	(general
		(thickness 1.6)
		(legacy_teardrops no)
	)
	(paper "A4")
	(title_block
		(title "Wiwynn_Tioga_Pass_MB.brd")
		(comment 1 "Tioga Pass / footprints 1220-1222 of 4770")
	)
	(layers
		(0 "F.Cu" signal "TOP")
		(4 "In1.Cu" signal "L2GND")
		(6 "In2.Cu" signal "L3")
		(8 "In3.Cu" signal "L4GND")
		(10 "In4.Cu" signal "L5")
		(12 "In5.Cu" signal "L6GND")
		(14 "In6.Cu" signal "L7VCC")
		(16 "In7.Cu" signal "L8VCC")
		(18 "In8.Cu" signal "L9GND")
		(20 "In9.Cu" signal "L10")
		(22 "In10.Cu" signal "L11GND")
		(24 "In11.Cu" signal "L12")
		(26 "In12.Cu" signal "L13GND")
		(2 "B.Cu" signal "BOTTOM")
		(9 "F.Adhes" user "F.Adhesive")
		(11 "B.Adhes" user "B.Adhesive")
		(13 "F.Paste" user "Package Geometry/Pastemask Top")
		(15 "B.Paste" user "Package Geometry/Pastemask Bottom")
		(5 "F.SilkS" user "Ref Des/Silkscreen Top")
		(7 "B.SilkS" user "Ref Des/Silkscreen Bottom")
		(1 "F.Mask" user "Board Geometry/Soldermask Top")
		(3 "B.Mask" user "Board Geometry/Soldermask Bottom")
		(17 "Dwgs.User" user "User.Drawings")
		(19 "Cmts.User" user "User.Comments")
		(21 "Eco1.User" user "User.Eco1")
		(23 "Eco2.User" user "User.Eco2")
		(25 "Edge.Cuts" user "Board Geometry/Outline")
		(27 "Margin" user)
		(31 "F.CrtYd" user "Package Geometry/Place Bound Top")
		(29 "B.CrtYd" user "Package Geometry/Place Bound Bottom")
		(35 "F.Fab" user "Ref Des/Assembly Top")
		(33 "B.Fab" user "Ref Des/Assembly Bottom")
	)
	(footprint ""
		(layer "F.Cu")
		(at 179.705 -64.135 180)
		(property "Reference" "R4E3"
			(at 0 0 180)
			(layer "F.SilkS")
			(hide yes)
			(effects
				(font
					(size 1.27 1.27)
				)
			)
		)
		(property "Value" ""
			(at 0 0 180)
			(layer "F.Fab")
			(effects
				(font
					(size 1.27 1.27)
				)
			)
		)
		(duplicate_pad_numbers_are_jumpers no)
		(fp_rect
			(start 0.2794 -0.1016)
			(end -0.2794 0.9906)
			(stroke
				(width 0)
				(type default)
			)
			(fill no)
			(layer "F.CrtYd")
		)
		(fp_line
			(start 0.2794 0.9906)
			(end 0.2794 -0.1016)
			(stroke
				(width 0.1)
				(type default)
			)
			(layer "F.Fab")
		)
		(fp_line
			(start 0.2794 -0.1016)
			(end -0.2794 -0.1016)
			(stroke
				(width 0.1)
				(type default)
			)
			(layer "F.Fab")
		)
		(fp_line
			(start -0.2794 0.9906)
			(end 0.2794 0.9906)
			(stroke
				(width 0.1)
				(type default)
			)
			(layer "F.Fab")
		)
		(fp_line
			(start -0.2794 -0.1016)
			(end -0.2794 0.9906)
			(stroke
				(width 0.1)
				(type default)
			)
			(layer "F.Fab")
		)
		(pad "1" smd rect
			(at 0 0 180)
			(size 0.508 0.508)
			(layers "F.Cu" "F.Mask" "F.Paste")
			(net "P3V3_STBY")
		)
		(pad "2" smd rect
			(at 0 0.889 180)
			(size 0.508 0.508)
			(layers "F.Cu" "F.Mask" "F.Paste")
			(net "IRQ_PVCCIN_CPU0_VRHOT_LVC3_R_N")
		)
		(zone
			(layer "F.Cu")
			(hatch none 0.5)
			(connect_pads
				(clearance 0)
			)
			(min_thickness 0.25)
			(keepout
				(tracks allowed)
				(vias not_allowed)
				(pads allowed)
				(copperpour not_allowed)
				(footprints allowed)
			)
			(placement
				(enabled no)
				(sheetname "")
			)
			(fill
				(thermal_gap 0.5)
				(thermal_bridge_width 0.5)
				(island_removal_mode 0)
			)
			(polygon
				(pts
					(xy 179.451 -64.389) (xy 179.959 -64.389) (xy 179.959 -64.77) (xy 179.451 -64.77)
				)
			)
		)
		(zone
			(layer "F.Cu")
			(hatch none 0.5)
			(connect_pads
				(clearance 0)
			)
			(min_thickness 0.25)
			(keepout
				(tracks not_allowed)
				(vias allowed)
				(pads allowed)
				(copperpour not_allowed)
				(footprints allowed)
			)
			(placement
				(enabled no)
				(sheetname "")
			)
			(fill
				(thermal_gap 0.5)
				(thermal_bridge_width 0.5)
				(island_removal_mode 0)
			)
			(polygon
				(pts
					(xy 179.451 -64.389) (xy 179.959 -64.389) (xy 179.959 -64.77) (xy 179.451 -64.77)
				)
			)
		)
	)
	(footprint ""
		(layer "F.Cu")
		(at 442.364876 -14.123924 90)
		(property "Reference" "R2U40"
			(at 0 0 90)
			(layer "F.SilkS")
			(hide yes)
			(effects
				(font
					(size 1.27 1.27)
				)
			)
		)
		(property "Value" ""
			(at 0 0 90)
			(layer "F.Fab")
			(effects
				(font
					(size 1.27 1.27)
				)
			)
		)
		(duplicate_pad_numbers_are_jumpers no)
		(fp_poly
			(pts
				(xy -0.2794 -0.1016) (xy 0.2794 -0.1016) (xy 0.2794 0.9906) (xy -0.2794 0.9906)
			)
			(stroke
				(width 0)
				(type default)
			)
			(fill no)
			(layer "F.CrtYd")
		)
		(fp_line
			(start 0.2794 -0.1016)
			(end -0.2794 -0.1016)
			(stroke
				(width 0.1)
				(type default)
			)
			(layer "F.Fab")
		)
		(fp_line
			(start -0.2794 -0.1016)
			(end -0.2794 0.9906)
			(stroke
				(width 0.1)
				(type default)
			)
			(layer "F.Fab")
		)
		(fp_line
			(start 0.2794 0.9906)
			(end 0.2794 -0.1016)
			(stroke
				(width 0.1)
				(type default)
			)
			(layer "F.Fab")
		)
		(fp_line
			(start -0.2794 0.9906)
			(end 0.2794 0.9906)
			(stroke
				(width 0.1)
				(type default)
			)
			(layer "F.Fab")
		)
		(pad "1" smd rect
			(at 0 0 90)
			(size 0.508 0.508)
			(layers "F.Cu" "F.Mask" "F.Paste")
			(net "PVCCIO_CPU0")
		)
		(pad "2" smd rect
			(at 0 0.889 90)
			(size 0.508 0.508)
			(layers "F.Cu" "F.Mask" "F.Paste")
			(net "H_CPU0_MEMABC_MEMHOT_G_N")
		)
		(zone
			(layer "F.Cu")
			(hatch none 0.5)
			(connect_pads
				(clearance 0)
			)
			(min_thickness 0.25)
			(keepout
				(tracks allowed)
				(vias not_allowed)
				(pads allowed)
				(copperpour not_allowed)
				(footprints allowed)
			)
			(placement
				(enabled no)
				(sheetname "")
			)
			(fill
				(thermal_gap 0.5)
				(thermal_bridge_width 0.5)
				(island_removal_mode 0)
			)
			(polygon
				(pts
					(xy 442.618876 -13.869924) (xy 442.618876 -14.377924) (xy 442.999876 -14.377924) (xy 442.999876 -13.869924)
				)
			)
		)
		(zone
			(layer "F.Cu")
			(hatch none 0.5)
			(connect_pads
				(clearance 0)
			)
			(min_thickness 0.25)
			(keepout
				(tracks not_allowed)
				(vias allowed)
				(pads allowed)
				(copperpour not_allowed)
				(footprints allowed)
			)
			(placement
				(enabled no)
				(sheetname "")
			)
			(fill
				(thermal_gap 0.5)
				(thermal_bridge_width 0.5)
				(island_removal_mode 0)
			)
			(polygon
				(pts
					(xy 442.999876 -13.869924) (xy 442.999876 -14.377924) (xy 442.618876 -14.377924) (xy 442.618876 -13.869924)
				)
			)
		)
	)
	(footprint ""
		(layer "F.Cu")
		(at 49.4284 -63.080392)
		(property "Reference" "C1E3"
			(at 0 0 0)
			(layer "F.SilkS")
			(hide yes)
			(effects
				(font
					(size 1.27 1.27)
				)
			)
		)
		(property "Value" ""
			(at 0 0 0)
			(layer "F.Fab")
			(effects
				(font
					(size 1.27 1.27)
				)
			)
		)
		(duplicate_pad_numbers_are_jumpers no)
		(fp_poly
			(pts
				(xy -0.4953 -0.2032) (xy 0.4953 -0.2032) (xy 0.4953 1.6002) (xy -0.4953 1.6002)
			)
			(stroke
				(width 0)
				(type default)
			)
			(fill no)
			(layer "F.CrtYd")
		)
		(fp_line
			(start -0.4953 -0.2032)
			(end 0.4953 -0.2032)
			(stroke
				(width 0.1)
				(type default)
			)
			(layer "F.Fab")
		)
		(fp_line
			(start -0.4953 1.6002)
			(end -0.4953 -0.2032)
			(stroke
				(width 0.1)
				(type default)
			)
			(layer "F.Fab")
		)
		(fp_line
			(start 0.4953 -0.2032)
			(end 0.4953 1.6002)
			(stroke
				(width 0.1)
				(type default)
			)
			(layer "F.Fab")
		)
		(fp_line
			(start 0.4953 1.6002)
			(end -0.4953 1.6002)
			(stroke
				(width 0.1)
				(type default)
			)
			(layer "F.Fab")
		)
		(pad "1" smd rect
			(at 0 0)
			(size 0.762 0.889)
			(layers "F.Cu" "F.Mask" "F.Paste")
			(net "PVCCIN_CPU1")
		)
		(pad "2" smd rect
			(at 0 1.397)
			(size 0.762 0.889)
			(layers "F.Cu" "F.Mask" "F.Paste")
			(net "GND")
		)
		(zone
			(layer "F.Cu")
			(hatch none 0.5)
			(connect_pads
				(clearance 0)
			)
			(min_thickness 0.25)
			(keepout
				(tracks not_allowed)
				(vias allowed)
				(pads allowed)
				(copperpour not_allowed)
				(footprints allowed)
			)
			(placement
				(enabled no)
				(sheetname "")
			)
			(fill
				(thermal_gap 0.5)
				(thermal_bridge_width 0.5)
				(island_removal_mode 0)
			)
			(polygon
				(pts
					(xy 49.0474 -62.635892) (xy 49.8094 -62.635892) (xy 49.8094 -62.127892) (xy 49.0474 -62.127892)
				)
			)
		)
	)
)
